(kicad_pcb
	(version 20241229)
	(generator "pcbnew")
	(generator_version "9.0")
	(general
		(thickness 1.63)
		(legacy_teardrops no)
	)
	(paper "A4")
	(title_block
		(title "CM4 Baseboard")
		(date "2026-01-05")
		(rev "1.1.1")
		(company "Antmicro Ltd")
		(comment 1 "www.antmicro.com")
		(comment 9 "footprints 365-369 of 506")
	)
	(layers
		(0 "F.Cu" signal)
		(4 "In1.Cu" power)
		(6 "In2.Cu" power)
		(8 "In3.Cu" signal)
		(10 "In4.Cu" signal)
		(2 "B.Cu" signal)
		(9 "F.Adhes" user "F.Adhesive")
		(11 "B.Adhes" user "B.Adhesive")
		(13 "F.Paste" user)
		(15 "B.Paste" user)
		(5 "F.SilkS" user "F.Silkscreen")
		(7 "B.SilkS" user "B.Silkscreen")
		(1 "F.Mask" user)
		(3 "B.Mask" user)
		(17 "Dwgs.User" user "User.Drawings")
		(19 "Cmts.User" user "User.Comments")
		(21 "Eco1.User" user "User.Eco1")
		(23 "Eco2.User" user "User.Eco2")
		(25 "Edge.Cuts" user)
		(27 "Margin" user)
		(31 "F.CrtYd" user "F.Courtyard")
		(29 "B.CrtYd" user "B.Courtyard")
		(35 "F.Fab" user)
		(33 "B.Fab" user)
	)
	(footprint "antmicro-footprints:SOD-523"
		(layer "B.Cu")
		(at 135.767962 146.2415 90)
		(property "Reference" "D603"
			(at 1.145 0.43 90)
			(layer "B.SilkS")
			(effects
				(font
					(size 0.7 0.7)
					(thickness 0.15)
				)
				(justify right bottom mirror)
			)
		)
		(property "Value" "PESD5Z5_0F"
			(at 0 -1.499 90)
			(layer "B.Fab")
			(effects
				(font
					(size 0.7 0.7)
					(thickness 0.15)
				)
				(justify right bottom mirror)
			)
		)
		(property "Datasheet" "https://assets.nexperia.com/documents/data-sheet/PESD5Z5_0.pdf"
			(at 0 0 90)
			(layer "B.Fab")
			(hide yes)
			(effects
				(font
					(size 1.27 1.27)
					(thickness 0.15)
				)
			)
		)
		(property "Manufacturer" "Nexperia"
			(at 0 0 90)
			(unlocked yes)
			(layer "B.Fab")
			(hide yes)
			(effects
				(font
					(size 1 1)
					(thickness 0.15)
				)
				(justify mirror)
			)
		)
		(property "MPN" "PESD5Z5.0F"
			(at 0 0 90)
			(unlocked yes)
			(layer "B.Fab")
			(hide yes)
			(effects
				(font
					(size 1 1)
					(thickness 0.15)
				)
				(justify mirror)
			)
		)
		(property "Author" "Antmicro"
			(at 0 0 90)
			(unlocked yes)
			(layer "B.Fab")
			(hide yes)
			(effects
				(font
					(size 1 1)
					(thickness 0.15)
				)
				(justify mirror)
			)
		)
		(property "License" "Apache-2.0"
			(at 0 0 90)
			(unlocked yes)
			(layer "B.Fab")
			(hide yes)
			(effects
				(font
					(size 1 1)
					(thickness 0.15)
				)
				(justify mirror)
			)
		)
		(sheetname "/CSI/")
		(sheetfile "csi.kicad_sch")
		(attr smd)
		(fp_line
			(start -0.35 0.5)
			(end -0.35 -0.5)
			(stroke
				(width 0.15)
				(type solid)
			)
			(layer "B.SilkS")
		)
		(fp_rect
			(start -1 0.6)
			(end 1 -0.6)
			(stroke
				(width 0.05)
				(type solid)
			)
			(fill no)
			(layer "B.CrtYd")
		)
		(fp_line
			(start -0.652 -0.423)
			(end 0.65 -0.423)
			(stroke
				(width 0.15)
				(type solid)
			)
			(layer "B.Fab")
		)
		(fp_line
			(start -0.652 -0.423)
			(end -0.652 0.425)
			(stroke
				(width 0.15)
				(type solid)
			)
			(layer "B.Fab")
		)
		(fp_line
			(start -0.35 0.4)
			(end -0.35 -0.4)
			(stroke
				(width 0.15)
				(type solid)
			)
			(layer "B.Fab")
		)
		(fp_line
			(start 0.65 0.425)
			(end 0.65 -0.423)
			(stroke
				(width 0.15)
				(type solid)
			)
			(layer "B.Fab")
		)
		(fp_line
			(start -0.652 0.425)
			(end 0.65 0.425)
			(stroke
				(width 0.15)
				(type solid)
			)
			(layer "B.Fab")
		)
		(fp_text user "Author: Antmicro"
			(at -1.276 -4.7 270)
			(layer "B.Fab")
			(effects
				(font
					(size 0.7 0.7)
					(thickness 0.15)
				)
				(justify left bottom mirror)
			)
		)
		(fp_text user "${REFERENCE}"
			(at -1.276 -3.499 270)
			(layer "B.Fab")
			(effects
				(font
					(size 0.7 0.7)
					(thickness 0.15)
				)
				(justify left bottom mirror)
			)
		)
		(fp_text user "License: Apache-2.0"
			(at -1.276 -5.9 270)
			(layer "B.Fab")
			(effects
				(font
					(size 0.7 0.7)
					(thickness 0.15)
				)
				(justify left bottom mirror)
			)
		)
		(pad "1" smd roundrect
			(at -0.701 0 90)
			(size 0.5 0.6)
			(layers "B.Cu" "B.Mask" "B.Paste")
			(roundrect_rratio 0.25)
			(net 19 "/CSI/CSI_3V3")
			(pinfunction "C")
			(pintype "passive")
		)
		(pad "2" smd roundrect
			(at 0.699 0 90)
			(size 0.5 0.6)
			(layers "B.Cu" "B.Mask" "B.Paste")
			(roundrect_rratio 0.25)
			(net 3 "GND")
			(pinfunction "A")
			(pintype "passive")
		)
	)
	(footprint "antmicro-footprints:C_0805_2012Metric"
		(layer "B.Cu")
		(at 48.867962 156.3665 -90)
		(descr "Capacitor SMD 0805")
		(tags "capacitor SMD 0805")
		(property "Reference" "C304"
			(at -5.04 -0.04 90)
			(layer "B.SilkS")
			(effects
				(font
					(size 0.7 0.7)
					(thickness 0.15)
				)
				(justify left bottom mirror)
			)
		)
		(property "Value" "C_22u_25V_0805"
			(at -2.055717 -1.963152 90)
			(layer "B.Fab")
			(effects
				(font
					(size 0.7 0.7)
					(thickness 0.15)
				)
				(justify left bottom mirror)
			)
		)
		(property "Datasheet" "https://product.samsungsem.com/mlcc/CL21A226MAYNNN.do"
			(at 0 0 270)
			(layer "B.Fab")
			(hide yes)
			(effects
				(font
					(size 1.27 1.27)
					(thickness 0.15)
				)
			)
		)
		(property "Manufacturer" "Samsung Electro-Mechanics"
			(at 0 0 270)
			(unlocked yes)
			(layer "B.Fab")
			(hide yes)
			(effects
				(font
					(size 1 1)
					(thickness 0.15)
				)
				(justify mirror)
			)
		)
		(property "MPN" "CL21A226MAYNNNE"
			(at 0 0 270)
			(unlocked yes)
			(layer "B.Fab")
			(hide yes)
			(effects
				(font
					(size 1 1)
					(thickness 0.15)
				)
				(justify mirror)
			)
		)
		(property "Val" "22u"
			(at 0 0 270)
			(unlocked yes)
			(layer "B.Fab")
			(hide yes)
			(effects
				(font
					(size 1 1)
					(thickness 0.15)
				)
				(justify mirror)
			)
		)
		(property "License" "Apache-2.0"
			(at 0 0 270)
			(unlocked yes)
			(layer "B.Fab")
			(hide yes)
			(effects
				(font
					(size 1 1)
					(thickness 0.15)
				)
				(justify mirror)
			)
		)
		(property "Author" "Antmicro"
			(at 0 0 270)
			(unlocked yes)
			(layer "B.Fab")
			(hide yes)
			(effects
				(font
					(size 1 1)
					(thickness 0.15)
				)
				(justify mirror)
			)
		)
		(property "Voltage" "25V"
			(at 0 0 270)
			(unlocked yes)
			(layer "B.Fab")
			(hide yes)
			(effects
				(font
					(size 1 1)
					(thickness 0.15)
				)
				(justify mirror)
			)
		)
		(property "Dielectric" "X5R"
			(at 0 0 270)
			(unlocked yes)
			(layer "B.Fab")
			(hide yes)
			(effects
				(font
					(size 1 1)
					(thickness 0.15)
				)
				(justify mirror)
			)
		)
		(property "Public" "False"
			(at 0 0 270)
			(unlocked yes)
			(layer "B.Fab")
			(hide yes)
			(effects
				(font
					(size 1 1)
					(thickness 0.15)
				)
				(justify mirror)
			)
		)
		(sheetname "/Supply/")
		(sheetfile "supply.kicad_sch")
		(attr smd)
		(fp_line
			(start -0.3 0.7)
			(end 0.3 0.7)
			(stroke
				(width 0.15)
				(type solid)
			)
			(layer "B.SilkS")
		)
		(fp_line
			(start -0.3 -0.7)
			(end 0.3 -0.7)
			(stroke
				(width 0.15)
				(type solid)
			)
			(layer "B.SilkS")
		)
		(fp_rect
			(start 1.95 0.9)
			(end -1.95 -0.9)
			(stroke
				(width 0.05)
				(type default)
			)
			(fill no)
			(layer "B.CrtYd")
		)
		(fp_rect
			(start -0.95 0.675)
			(end 0.95 -0.675)
			(stroke
				(width 0.15)
				(type solid)
			)
			(fill no)
			(layer "B.Fab")
		)
		(fp_text user "License: Apache-2.0"
			(at -1.9 -4.947 90)
			(layer "B.Fab")
			(effects
				(font
					(size 0.7 0.7)
					(thickness 0.15)
				)
				(justify left bottom mirror)
			)
		)
		(fp_text user "${REFERENCE}"
			(at -1.9 -3.947 90)
			(layer "B.Fab")
			(effects
				(font
					(size 0.7 0.7)
					(thickness 0.15)
				)
				(justify left bottom mirror)
			)
		)
		(fp_text user "Author: Antmicro"
			(at -1.9 -5.947 90)
			(layer "B.Fab")
			(effects
				(font
					(size 0.7 0.7)
					(thickness 0.15)
				)
				(justify left bottom mirror)
			)
		)
		(pad "1" smd roundrect
			(at -1.1 0 270)
			(size 1.2 1.3)
			(layers "B.Cu" "B.Mask" "B.Paste")
			(roundrect_rratio 0.25)
			(net 43 "VCC")
			(pintype "passive")
		)
		(pad "2" smd roundrect
			(at 1.1 0 270)
			(size 1.2 1.3)
			(layers "B.Cu" "B.Mask" "B.Paste")
			(roundrect_rratio 0.25)
			(net 3 "GND")
			(pintype "passive")
		)
	)
	(footprint "antmicro-footprints:R_0402_1005Metric"
		(layer "B.Cu")
		(at 45.332962 161.8375 180)
		(descr "Resistor SMD 0402")
		(tags "resistor SMD 0402")
		(property "Reference" "R304"
			(at -1.475 0.521 0)
			(layer "B.SilkS")
			(effects
				(font
					(size 0.7 0.7)
					(thickness 0.15)
				)
				(justify left bottom mirror)
			)
		)
		(property "Value" "R_470k_0402"
			(at -1.011843 -1.772047 0)
			(layer "B.Fab")
			(effects
				(font
					(size 0.7 0.7)
					(thickness 0.15)
				)
				(justify left bottom mirror)
			)
		)
		(property "Datasheet" "https://www.bourns.com/docs/product-datasheets/cr.pdf"
			(at 0 0 180)
			(layer "B.Fab")
			(hide yes)
			(effects
				(font
					(size 1.27 1.27)
					(thickness 0.15)
				)
			)
		)
		(property "MPN" "CR0402-FX-4703GLF"
			(at 0 0 180)
			(unlocked yes)
			(layer "B.Fab")
			(hide yes)
			(effects
				(font
					(size 1 1)
					(thickness 0.15)
				)
				(justify mirror)
			)
		)
		(property "Manufacturer" "Bourns"
			(at 0 0 180)
			(unlocked yes)
			(layer "B.Fab")
			(hide yes)
			(effects
				(font
					(size 1 1)
					(thickness 0.15)
				)
				(justify mirror)
			)
		)
		(property "License" "Apache-2.0"
			(at 0 0 180)
			(unlocked yes)
			(layer "B.Fab")
			(hide yes)
			(effects
				(font
					(size 1 1)
					(thickness 0.15)
				)
				(justify mirror)
			)
		)
		(property "Author" "Antmicro"
			(at 0 0 180)
			(unlocked yes)
			(layer "B.Fab")
			(hide yes)
			(effects
				(font
					(size 1 1)
					(thickness 0.15)
				)
				(justify mirror)
			)
		)
		(property "Val" "470k"
			(at 0 0 180)
			(unlocked yes)
			(layer "B.Fab")
			(hide yes)
			(effects
				(font
					(size 1 1)
					(thickness 0.15)
				)
				(justify mirror)
			)
		)
		(property "Tolerance" "1%"
			(at 0 0 180)
			(unlocked yes)
			(layer "B.Fab")
			(hide yes)
			(effects
				(font
					(size 1 1)
					(thickness 0.15)
				)
				(justify mirror)
			)
		)
		(sheetname "/Supply/")
		(sheetfile "supply.kicad_sch")
		(attr smd)
		(fp_rect
			(start -0.925 0.47)
			(end 0.925 -0.47)
			(stroke
				(width 0.05)
				(type default)
			)
			(fill no)
			(layer "B.CrtYd")
		)
		(fp_rect
			(start -0.5 0.25)
			(end 0.5 -0.25)
			(stroke
				(width 0.15)
				(type solid)
			)
			(fill no)
			(layer "B.Fab")
		)
		(fp_text user "${REFERENCE}"
			(at -0.95 -3.168 0)
			(layer "B.Fab")
			(effects
				(font
					(size 0.7 0.7)
					(thickness 0.15)
				)
				(justify left bottom mirror)
			)
		)
		(fp_text user "Author: Antmicro"
			(at -0.95 -4.169 0)
			(layer "B.Fab")
			(effects
				(font
					(size 0.7 0.7)
					(thickness 0.15)
				)
				(justify left bottom mirror)
			)
		)
		(fp_text user "License: Apache-2.0"
			(at -0.95 -5.169 0)
			(layer "B.Fab")
			(effects
				(font
					(size 0.7 0.7)
					(thickness 0.15)
				)
				(justify left bottom mirror)
			)
		)
		(pad "1" smd roundrect
			(at -0.48 0 180)
			(size 0.59 0.64)
			(layers "B.Cu" "B.Mask" "B.Paste")
			(roundrect_rratio 0.25)
			(net 3 "GND")
			(pintype "passive")
		)
		(pad "2" smd roundrect
			(at 0.48 0 180)
			(size 0.59 0.64)
			(layers "B.Cu" "B.Mask" "B.Paste")
			(roundrect_rratio 0.25)
			(net 333 "Net-(Q301-BIAS)")
			(pintype "passive")
		)
	)
	(footprint "antmicro-footprints:D_SOD-123F"
		(layer "B.Cu")
		(at 56.767962 115.1915 90)
		(property "Reference" "D403"
			(at -1.205 -1.16 90)
			(layer "B.SilkS")
			(effects
				(font
					(size 0.7 0.7)
					(thickness 0.15)
				)
				(justify right bottom mirror)
			)
		)
		(property "Value" "PTVS58VS1UR,115"
			(at 0 -2.1 90)
			(layer "B.Fab")
			(effects
				(font
					(size 0.7 0.7)
					(thickness 0.15)
				)
				(justify right bottom mirror)
			)
		)
		(property "Datasheet" "https://assets.nexperia.com/documents/data-sheet/PTVSXS1UR_SER.pdf"
			(at 0 0 90)
			(layer "B.Fab")
			(hide yes)
			(effects
				(font
					(size 1.27 1.27)
					(thickness 0.15)
				)
			)
		)
		(property "MPN" "PTVS58VS1UR,115"
			(at 0 0 90)
			(unlocked yes)
			(layer "B.Fab")
			(hide yes)
			(effects
				(font
					(size 1 1)
					(thickness 0.15)
				)
				(justify mirror)
			)
		)
		(property "Manufacturer" "Nexperia"
			(at 0 0 90)
			(unlocked yes)
			(layer "B.Fab")
			(hide yes)
			(effects
				(font
					(size 1 1)
					(thickness 0.15)
				)
				(justify mirror)
			)
		)
		(property "Author" "Antmicro"
			(at 0 0 90)
			(unlocked yes)
			(layer "B.Fab")
			(hide yes)
			(effects
				(font
					(size 1 1)
					(thickness 0.15)
				)
				(justify mirror)
			)
		)
		(property "License" "Apache-2.0"
			(at 0 0 90)
			(unlocked yes)
			(layer "B.Fab")
			(hide yes)
			(effects
				(font
					(size 1 1)
					(thickness 0.15)
				)
				(justify mirror)
			)
		)
		(sheetname "/Ethernet/")
		(sheetfile "ethernet.kicad_sch")
		(attr smd)
		(fp_line
			(start -0.65 0.6)
			(end -0.65 -0.6)
			(stroke
				(width 0.15)
				(type solid)
			)
			(layer "B.SilkS")
		)
		(fp_line
			(start 2.2 -1.1)
			(end -2.21 -1.1)
			(stroke
				(width 0.05)
				(type solid)
			)
			(layer "B.CrtYd")
		)
		(fp_line
			(start -2.21 -1.1)
			(end -2.21 1.1)
			(stroke
				(width 0.05)
				(type solid)
			)
			(layer "B.CrtYd")
		)
		(fp_line
			(start 2.2 1.1)
			(end 2.2 -1.1)
			(stroke
				(width 0.05)
				(type solid)
			)
			(layer "B.CrtYd")
		)
		(fp_line
			(start 2.2 1.1)
			(end -2.21 1.1)
			(stroke
				(width 0.05)
				(type solid)
			)
			(layer "B.CrtYd")
		)
		(fp_line
			(start -0.8 0.8)
			(end -0.8 -0.8)
			(stroke
				(width 0.1)
				(type solid)
			)
			(layer "B.Fab")
		)
		(fp_rect
			(start -1.75 0.802)
			(end 1.749 -0.8)
			(stroke
				(width 0.1)
				(type solid)
			)
			(fill no)
			(layer "B.Fab")
		)
		(fp_text user "Author: Antmicro"
			(at -2.202 -4.998 270)
			(layer "B.Fab")
			(effects
				(font
					(size 0.7 0.7)
					(thickness 0.15)
				)
				(justify left bottom mirror)
			)
		)
		(fp_text user "License: Apache-2.0"
			(at -2.202 -6.2 270)
			(layer "B.Fab")
			(effects
				(font
					(size 0.7 0.7)
					(thickness 0.15)
				)
				(justify left bottom mirror)
			)
		)
		(fp_text user "${REFERENCE}"
			(at -2.202 -3.798 270)
			(layer "B.Fab")
			(effects
				(font
					(size 0.7 0.7)
					(thickness 0.15)
				)
				(justify left bottom mirror)
			)
		)
		(pad "1" smd roundrect
			(at -1.401 0 90)
			(size 1.2 1.2)
			(layers "B.Cu" "B.Mask" "B.Paste")
			(roundrect_rratio 0.25)
			(net 33 "/Ethernet/VDD")
			(pinfunction "C")
			(pintype "passive")
		)
		(pad "2" smd roundrect
			(at 1.398 0 90)
			(size 1.2 1.2)
			(layers "B.Cu" "B.Mask" "B.Paste")
			(roundrect_rratio 0.25)
			(net 90 "/Ethernet/VSS")
			(pinfunction "A")
			(pintype "passive")
		)
	)
	(footprint "antmicro-footprints:R_0402_1005Metric"
		(layer "B.Cu")
		(at 84.667962 124.6665)
		(descr "Resistor SMD 0402")
		(tags "resistor SMD 0402")
		(property "Reference" "R913"
			(at -4.25 0.39 0)
			(layer "B.SilkS")
			(effects
				(font
					(size 0.7 0.7)
					(thickness 0.15)
				)
				(justify right bottom mirror)
			)
		)
		(property "Value" "R_2k2_0402"
			(at -1.011843 -1.772047 0)
			(layer "B.Fab")
			(effects
				(font
					(size 0.7 0.7)
					(thickness 0.15)
				)
				(justify right bottom mirror)
			)
		)
		(property "Datasheet" "https://www.bourns.com/docs/product-datasheets/cr.pdf"
			(at 0 0 0)
			(layer "B.Fab")
			(hide yes)
			(effects
				(font
					(size 1.27 1.27)
					(thickness 0.15)
				)
			)
		)
		(property "MPN" "CR0402-FX-2201GLF"
			(at 0 0 0)
			(unlocked yes)
			(layer "B.Fab")
			(hide yes)
			(effects
				(font
					(size 1 1)
					(thickness 0.15)
				)
				(justify mirror)
			)
		)
		(property "Manufacturer" "Bourns"
			(at 0 0 0)
			(unlocked yes)
			(layer "B.Fab")
			(hide yes)
			(effects
				(font
					(size 1 1)
					(thickness 0.15)
				)
				(justify mirror)
			)
		)
		(property "License" "Apache-2.0"
			(at 0 0 0)
			(unlocked yes)
			(layer "B.Fab")
			(hide yes)
			(effects
				(font
					(size 1 1)
					(thickness 0.15)
				)
				(justify mirror)
			)
		)
		(property "Author" "Antmicro"
			(at 0 0 0)
			(unlocked yes)
			(layer "B.Fab")
			(hide yes)
			(effects
				(font
					(size 1 1)
					(thickness 0.15)
				)
				(justify mirror)
			)
		)
		(property "Val" "2k2"
			(at 0 0 0)
			(unlocked yes)
			(layer "B.Fab")
			(hide yes)
			(effects
				(font
					(size 1 1)
					(thickness 0.15)
				)
				(justify mirror)
			)
		)
		(property "Tolerance" "1%"
			(at 0 0 0)
			(unlocked yes)
			(layer "B.Fab")
			(hide yes)
			(effects
				(font
					(size 1 1)
					(thickness 0.15)
				)
				(justify mirror)
			)
		)
		(sheetname "/USB/")
		(sheetfile "usb.kicad_sch")
		(attr smd)
		(fp_rect
			(start -0.925 0.47)
			(end 0.925 -0.47)
			(stroke
				(width 0.05)
				(type default)
			)
			(fill no)
			(layer "B.CrtYd")
		)
		(fp_rect
			(start -0.5 0.25)
			(end 0.5 -0.25)
			(stroke
				(width 0.15)
				(type solid)
			)
			(fill no)
			(layer "B.Fab")
		)
		(fp_text user "Author: Antmicro"
			(at -0.95 -4.169 180)
			(layer "B.Fab")
			(effects
				(font
					(size 0.7 0.7)
					(thickness 0.15)
				)
				(justify left bottom mirror)
			)
		)
		(fp_text user "${REFERENCE}"
			(at -0.95 -3.168 180)
			(layer "B.Fab")
			(effects
				(font
					(size 0.7 0.7)
					(thickness 0.15)
				)
				(justify left bottom mirror)
			)
		)
		(fp_text user "License: Apache-2.0"
			(at -0.95 -5.169 180)
			(layer "B.Fab")
			(effects
				(font
					(size 0.7 0.7)
					(thickness 0.15)
				)
				(justify left bottom mirror)
			)
		)
		(pad "1" smd roundrect
			(at -0.48 0)
			(size 0.59 0.64)
			(layers "B.Cu" "B.Mask" "B.Paste")
			(roundrect_rratio 0.25)
			(net 3 "GND")
			(pintype "passive")
		)
		(pad "2" smd roundrect
			(at 0.48 0)
			(size 0.59 0.64)
			(layers "B.Cu" "B.Mask" "B.Paste")
			(roundrect_rratio 0.25)
			(net 344 "/USB/FB_FTDI")
			(pintype "passive")
		)
	)
)
